FILE_TYPE = CONNECTIVITY;
{Allegro Design Entry HDL 16.6-p007 (v16-6-112F) 10/10/2012}
"PAGE_NUMBER" = 160;
0"NC";
1"P3V3_STBY\g";
2"P3V3_STBY\g";
3"SMB_SLOTX24_STBY_LVC3_SDA_R";
4"SMB_LAN_STBY_LVC3_SDA_R";
5"SMB_SLOTX24_STBY_LVC3_SCL_R";
6"SMB_SLOTX24_BMC_STBY_LVC3_SDA";
7"SMB_SLOTX24_BMC_STBY_LVC3_SCL";
8"SMB_LAN_STBY_LVC3_SCL_R";
9"SMB_LAN_STBY_LVC3_SCL";
10"SMB_LAN_STBY_LVC3_SDA";
%"RES"
"1","(-3350,4600)","0","mstr_discrete","I4";
;
TOLERANCE"1%"
MATERIAL"CHIP"
LOCATION"R1T8"
VALUE"20.0"
WATTAGE"1/16W"
PACK_TYPE"0402"
PART_NUMBER"G21796-173"
BOM_COST"SM_CONTROLLER"
CDS_LIB"mstr_discrete"
CDS_SEC"1"
$SEC"1"
CDS_LOCATION"R1T8"
ROOM"SMBUS";
"B"
$PN"2"6;
"A"
$PN"1"3;
%"RES"
"2","(-4000,4975)","0","mstr_discrete","I46";
;
CDS_SEC"1"
WATTAGE"1/16W"
LOCATION"R1T3"
VALUE"665"
MATERIAL"CHIP"
PACK_TYPE"0402"
PART_NUMBER"G21796-235"
TOLERANCE"1.0%"
SKU"B"
BOM_COST"SM_CONTROLLER"
CDS_LIB"mstr_discrete"
CDS_LOCATION"R1T3"
ROOM"SMBUS"
SEC"1"
SEC_TYPE"0402";
"A"
$PN"1"2;
"B"
$PN"2"3;
%"P3V3_STBY"
"1","(-3650,5275)","0","mstr_symbols","I47";
;
VOLTAGE"3.3V"
CDS_LIB"mstr_symbols"
SIZE"1B"
BODY_TYPE"PLUMBING"
HDL_POWER"P3V3_STBY";
"G\NAC"1;
%"P3V3_STBY"
"1","(-4000,5275)","0","mstr_symbols","I48";
;
VOLTAGE"3.3V"
CDS_LIB"mstr_symbols"
SIZE"1B"
BODY_TYPE"PLUMBING"
HDL_POWER"P3V3_STBY";
"G\NAC"2;
%"RES"
"2","(-3650,4975)","0","mstr_discrete","I49";
;
CDS_SEC"1"
LOCATION"R1T2"
VALUE"665"
MATERIAL"CHIP"
WATTAGE"1/16W"
PACK_TYPE"0402"
TOLERANCE"1.0%"
PART_NUMBER"G21796-235"
SKU"B"
BOM_COST"SM_CONTROLLER"
CDS_LIB"mstr_discrete"
CDS_LOCATION"R1T2"
ROOM"SMBUS"
SEC"1"
SEC_TYPE"0402";
"A"
$PN"1"1;
"B"
$PN"2"5;
%"RES"
"1","(-3350,4425)","0","mstr_discrete","I50";
;
TOLERANCE"1%"
MATERIAL"CHIP"
LOCATION"R1T7"
WATTAGE"1/16W"
VALUE"20.0"
PACK_TYPE"0402"
PART_NUMBER"G21796-173"
BOM_COST"SM_CONTROLLER"
CDS_LIB"mstr_discrete"
CDS_SEC"1"
$SEC"1"
CDS_LOCATION"R1T7"
ROOM"SMBUS";
"B"
$PN"2"7;
"A"
$PN"1"5;
%"RES"
"1","(-3350,3700)","0","mstr_discrete","I51";
;
TOLERANCE"1%"
WATTAGE"1/16W"
VALUE"20.0"
MATERIAL"CHIP"
LOCATION"R9F23"
PART_NUMBER"G21796-173"
PACK_TYPE"0402"
BOM_COST"SM_CONTROLLER"
CDS_LIB"mstr_discrete"
CDS_SEC"1"
$SEC"1"
CDS_LOCATION"R9F23"
ROOM"SMBUS";
"B"
$PN"2"10;
"A"
$PN"1"4;
%"RES"
"1","(-3350,3525)","0","mstr_discrete","I52";
;
MATERIAL"CHIP"
LOCATION"R9F22"
PART_NUMBER"G21796-173"
TOLERANCE"1%"
VALUE"20.0"
WATTAGE"1/16W"
PACK_TYPE"0402"
BOM_COST"SM_CONTROLLER"
CDS_LIB"mstr_discrete"
CDS_SEC"1"
$SEC"1"
CDS_LOCATION"R9F22"
ROOM"SMBUS";
"B"
$PN"2"9;
"A"
$PN"1"8;
END.
